(kicad_pcb
	(version 20260206)
	(generator "pcbnew")
	(generator_version "10.0")
	(general
		(thickness 1.6)
		(legacy_teardrops no)
	)
	(paper "A4")
	(title_block
		(title "Bryce Canyon_IOM_IOC_16318-2_OCP.brd")
		(comment 1 "Bryce Canyon / footprints 1020-1026 of 1605")
	)
	(layers
		(0 "F.Cu" signal "TOP")
		(4 "In1.Cu" signal "L2GND")
		(6 "In2.Cu" signal "L3")
		(8 "In3.Cu" signal "L4VCC")
		(10 "In4.Cu" signal "L5VCC")
		(12 "In5.Cu" signal "L6")
		(14 "In6.Cu" signal "L7GND")
		(2 "B.Cu" signal "BOTTOM")
		(9 "F.Adhes" user "F.Adhesive")
		(11 "B.Adhes" user "B.Adhesive")
		(13 "F.Paste" user "Package Geometry/Pastemask Top")
		(15 "B.Paste" user "Package Geometry/Pastemask Bottom")
		(5 "F.SilkS" user "Ref Des/Silkscreen Top")
		(7 "B.SilkS" user "Ref Des/Silkscreen Bottom")
		(1 "F.Mask" user "Board Geometry/Soldermask Top")
		(3 "B.Mask" user "Board Geometry/Soldermask Bottom")
		(17 "Dwgs.User" user "User.Drawings")
		(19 "Cmts.User" user "User.Comments")
		(21 "Eco1.User" user "User.Eco1")
		(23 "Eco2.User" user "User.Eco2")
		(25 "Edge.Cuts" user "Board Geometry/Outline")
		(27 "Margin" user)
		(31 "F.CrtYd" user "Package Geometry/Place Bound Top")
		(29 "B.CrtYd" user "Package Geometry/Place Bound Bottom")
		(35 "F.Fab" user "Ref Des/Assembly Top")
		(33 "B.Fab" user "Ref Des/Assembly Bottom")
	)
	(footprint ""
		(layer "B.Cu")
		(at 32.7914 -150.9522 180)
		(property "Reference" "C92"
			(at 0 0 0)
			(layer "B.SilkS")
			(hide yes)
			(effects
				(font
					(size 1.27 1.27)
				)
				(justify mirror)
			)
		)
		(property "Value" "SC1U16V3KX-5GP"
			(at 0 -2.8194 180)
			(unlocked yes)
			(layer "B.Fab")
			(hide yes)
			(effects
				(font
					(size 1.016 1.016)
					(thickness 0.1524)
				)
				(justify mirror)
			)
		)
		(property "Device Type" "C603H36"
			(at 0 -4.3434 180)
			(unlocked yes)
			(layer "B.Fab")
			(hide yes)
			(effects
				(font
					(size 1.016 1.016)
					(thickness 0.1524)
				)
				(justify mirror)
			)
		)
		(duplicate_pad_numbers_are_jumpers no)
		(fp_line
			(start -0.508 0)
			(end 0.508 0)
			(stroke
				(width 0.2032)
				(type default)
			)
			(layer "B.SilkS")
		)
		(fp_rect
			(start 0.5842 1.3335)
			(end -0.5842 -1.3335)
			(stroke
				(width 0)
				(type default)
			)
			(fill no)
			(layer "B.CrtYd")
		)
		(fp_rect
			(start 0.5842 1.3335)
			(end -0.5842 -1.3335)
			(stroke
				(width 0)
				(type default)
			)
			(fill no)
			(layer "B.Fab")
		)
		(pad "1" smd custom
			(at 0 -0.762)
			(size 0.2159 0.2159)
			(layers "B.Cu" "B.Mask" "B.Paste")
			(net "MPLLAV33")
			(options
				(clearance outline)
				(anchor circle)
			)
			(primitives
				(gr_poly
					(pts
						(arc
							(start -0.3302 0.4318)
							(mid -0.402042 0.402042)
							(end -0.4318 0.3302)
						)
						(arc
							(start -0.4318 -0.3302)
							(mid -0.402042 -0.402042)
							(end -0.3302 -0.4318)
						)
						(arc
							(start 0.3302 -0.4318)
							(mid 0.402042 -0.402042)
							(end 0.4318 -0.3302)
						)
						(arc
							(start 0.4318 0.3302)
							(mid 0.402042 0.402042)
							(end 0.3302 0.4318)
						)
					)
					(width 0)
					(fill yes)
				)
			)
		)
		(pad "2" smd custom
			(at 0 0.762)
			(size 0.2159 0.2159)
			(layers "B.Cu" "B.Mask" "B.Paste")
			(net "GND")
			(options
				(clearance outline)
				(anchor circle)
			)
			(primitives
				(gr_poly
					(pts
						(arc
							(start -0.3302 0.4318)
							(mid -0.402042 0.402042)
							(end -0.4318 0.3302)
						)
						(arc
							(start -0.4318 -0.3302)
							(mid -0.402042 -0.402042)
							(end -0.3302 -0.4318)
						)
						(arc
							(start 0.3302 -0.4318)
							(mid 0.402042 -0.402042)
							(end 0.4318 -0.3302)
						)
						(arc
							(start 0.4318 0.3302)
							(mid 0.402042 0.402042)
							(end 0.3302 0.4318)
						)
					)
					(width 0)
					(fill yes)
				)
			)
		)
	)
	(footprint ""
		(layer "B.Cu")
		(at 124.835666 -7.733792 -90)
		(property "Reference" "R433"
			(at 0 0 90)
			(layer "B.SilkS")
			(hide yes)
			(effects
				(font
					(size 1.27 1.27)
				)
				(justify mirror)
			)
		)
		(property "Value" "10KR2F-2-GP"
			(at -0.064008 -3.993896 270)
			(unlocked yes)
			(layer "B.Fab")
			(hide yes)
			(effects
				(font
					(size 1.016 1.016)
					(thickness 0.1524)
				)
				(justify mirror)
			)
		)
		(property "Device Type" "R402H16"
			(at -0.064008 -5.517896 270)
			(unlocked yes)
			(layer "B.Fab")
			(hide yes)
			(effects
				(font
					(size 1.016 1.016)
					(thickness 0.1524)
				)
				(justify mirror)
			)
		)
		(duplicate_pad_numbers_are_jumpers no)
		(fp_line
			(start -0.508 -0.9398)
			(end 0.508 -0.9398)
			(stroke
				(width 0.1524)
				(type default)
			)
			(layer "B.SilkS")
		)
		(fp_line
			(start 0.508 -0.9398)
			(end 0.508 0.9398)
			(stroke
				(width 0.1524)
				(type default)
			)
			(layer "B.SilkS")
		)
		(fp_rect
			(start 0.508 0.9398)
			(end -0.508 -0.9398)
			(stroke
				(width 0)
				(type default)
			)
			(fill no)
			(layer "B.CrtYd")
		)
		(fp_rect
			(start 0.508 0.9398)
			(end -0.508 -0.9398)
			(stroke
				(width 0)
				(type default)
			)
			(fill no)
			(layer "B.Fab")
		)
		(pad "1" smd custom
			(at 0 -0.4445 90)
			(size 0.1397 0.1397)
			(layers "B.Cu" "B.Mask" "B.Paste")
			(net "P12V_STBY")
			(options
				(clearance outline)
				(anchor circle)
			)
			(primitives
				(gr_poly
					(pts
						(arc
							(start -0.1778 0.2794)
							(mid -0.249642 0.249642)
							(end -0.2794 0.1778)
						)
						(arc
							(start -0.2794 -0.1778)
							(mid -0.249642 -0.249642)
							(end -0.1778 -0.2794)
						)
						(arc
							(start 0.1778 -0.2794)
							(mid 0.249642 -0.249642)
							(end 0.2794 -0.1778)
						)
						(arc
							(start 0.2794 0.1778)
							(mid 0.249642 0.249642)
							(end 0.1778 0.2794)
						)
					)
					(width 0)
					(fill yes)
				)
			)
		)
		(pad "2" smd custom
			(at 0 0.4445 90)
			(size 0.1397 0.1397)
			(layers "B.Cu" "B.Mask" "B.Paste")
			(net "P12V_IOM_PGOOD")
			(options
				(clearance outline)
				(anchor circle)
			)
			(primitives
				(gr_poly
					(pts
						(arc
							(start -0.1778 0.2794)
							(mid -0.249642 0.249642)
							(end -0.2794 0.1778)
						)
						(arc
							(start -0.2794 -0.1778)
							(mid -0.249642 -0.249642)
							(end -0.1778 -0.2794)
						)
						(arc
							(start 0.1778 -0.2794)
							(mid 0.249642 -0.249642)
							(end 0.2794 -0.1778)
						)
						(arc
							(start 0.2794 0.1778)
							(mid 0.249642 0.249642)
							(end 0.1778 0.2794)
						)
					)
					(width 0)
					(fill yes)
				)
			)
		)
	)
	(footprint ""
		(layer "B.Cu")
		(at 60.4774 -148.5138 180)
		(property "Reference" "R384"
			(at 0 0 0)
			(layer "B.SilkS")
			(hide yes)
			(effects
				(font
					(size 1.27 1.27)
				)
				(justify mirror)
			)
		)
		(property "Value" "4K7R2F-GP"
			(at -0.064008 -3.993896 180)
			(unlocked yes)
			(layer "B.Fab")
			(hide yes)
			(effects
				(font
					(size 1.016 1.016)
					(thickness 0.1524)
				)
				(justify mirror)
			)
		)
		(property "Device Type" "R402H16"
			(at -0.064008 -5.517896 180)
			(unlocked yes)
			(layer "B.Fab")
			(hide yes)
			(effects
				(font
					(size 1.016 1.016)
					(thickness 0.1524)
				)
				(justify mirror)
			)
		)
		(duplicate_pad_numbers_are_jumpers no)
		(fp_line
			(start 0.508 -0.9398)
			(end 0.508 0.9398)
			(stroke
				(width 0.1524)
				(type default)
			)
			(layer "B.SilkS")
		)
		(fp_line
			(start -0.508 -0.9398)
			(end 0.508 -0.9398)
			(stroke
				(width 0.1524)
				(type default)
			)
			(layer "B.SilkS")
		)
		(fp_rect
			(start 0.508 0.9398)
			(end -0.508 -0.9398)
			(stroke
				(width 0)
				(type default)
			)
			(fill no)
			(layer "B.CrtYd")
		)
		(fp_rect
			(start 0.508 0.9398)
			(end -0.508 -0.9398)
			(stroke
				(width 0)
				(type default)
			)
			(fill no)
			(layer "B.Fab")
		)
		(pad "1" smd custom
			(at 0 -0.4445)
			(size 0.1397 0.1397)
			(layers "B.Cu" "B.Mask" "B.Paste")
			(net "P3V3_STBY")
			(options
				(clearance outline)
				(anchor circle)
			)
			(primitives
				(gr_poly
					(pts
						(arc
							(start -0.1778 0.2794)
							(mid -0.249642 0.249642)
							(end -0.2794 0.1778)
						)
						(arc
							(start -0.2794 -0.1778)
							(mid -0.249642 -0.249642)
							(end -0.1778 -0.2794)
						)
						(arc
							(start 0.1778 -0.2794)
							(mid 0.249642 -0.249642)
							(end 0.2794 -0.1778)
						)
						(arc
							(start 0.2794 0.1778)
							(mid 0.249642 0.249642)
							(end 0.1778 0.2794)
						)
					)
					(width 0)
					(fill yes)
				)
			)
		)
		(pad "2" smd custom
			(at 0 0.4445)
			(size 0.1397 0.1397)
			(layers "B.Cu" "B.Mask" "B.Paste")
			(net "MAC1_TXD3")
			(options
				(clearance outline)
				(anchor circle)
			)
			(primitives
				(gr_poly
					(pts
						(arc
							(start -0.1778 0.2794)
							(mid -0.249642 0.249642)
							(end -0.2794 0.1778)
						)
						(arc
							(start -0.2794 -0.1778)
							(mid -0.249642 -0.249642)
							(end -0.1778 -0.2794)
						)
						(arc
							(start 0.1778 -0.2794)
							(mid 0.249642 -0.249642)
							(end 0.2794 -0.1778)
						)
						(arc
							(start 0.2794 0.1778)
							(mid 0.249642 0.249642)
							(end 0.1778 0.2794)
						)
					)
					(width 0)
					(fill yes)
				)
			)
		)
	)
	(footprint ""
		(layer "B.Cu")
		(at 19.15287 -131.007358 180)
		(property "Reference" "R236"
			(at 0 0 0)
			(layer "B.SilkS")
			(hide yes)
			(effects
				(font
					(size 1.27 1.27)
				)
				(justify mirror)
			)
		)
		(property "Value" "120R2F-GP"
			(at -0.064008 -3.993896 180)
			(unlocked yes)
			(layer "B.Fab")
			(hide yes)
			(effects
				(font
					(size 1.016 1.016)
					(thickness 0.1524)
				)
				(justify mirror)
			)
		)
		(property "Device Type" "R402H16"
			(at -0.064008 -5.517896 180)
			(unlocked yes)
			(layer "B.Fab")
			(hide yes)
			(effects
				(font
					(size 1.016 1.016)
					(thickness 0.1524)
				)
				(justify mirror)
			)
		)
		(duplicate_pad_numbers_are_jumpers no)
		(fp_line
			(start 0.508 -0.9398)
			(end 0.508 0.9398)
			(stroke
				(width 0.1524)
				(type default)
			)
			(layer "B.SilkS")
		)
		(fp_line
			(start -0.508 -0.9398)
			(end 0.508 -0.9398)
			(stroke
				(width 0.1524)
				(type default)
			)
			(layer "B.SilkS")
		)
		(fp_rect
			(start 0.508 0.9398)
			(end -0.508 -0.9398)
			(stroke
				(width 0)
				(type default)
			)
			(fill no)
			(layer "B.CrtYd")
		)
		(fp_rect
			(start 0.508 0.9398)
			(end -0.508 -0.9398)
			(stroke
				(width 0)
				(type default)
			)
			(fill no)
			(layer "B.Fab")
		)
		(pad "1" smd custom
			(at 0 -0.4445)
			(size 0.1397 0.1397)
			(layers "B.Cu" "B.Mask" "B.Paste")
			(net "MEMA_1")
			(options
				(clearance outline)
				(anchor circle)
			)
			(primitives
				(gr_poly
					(pts
						(arc
							(start -0.1778 0.2794)
							(mid -0.249642 0.249642)
							(end -0.2794 0.1778)
						)
						(arc
							(start -0.2794 -0.1778)
							(mid -0.249642 -0.249642)
							(end -0.1778 -0.2794)
						)
						(arc
							(start 0.1778 -0.2794)
							(mid 0.249642 -0.249642)
							(end 0.2794 -0.1778)
						)
						(arc
							(start 0.2794 0.1778)
							(mid 0.249642 0.249642)
							(end 0.1778 0.2794)
						)
					)
					(width 0)
					(fill yes)
				)
			)
		)
		(pad "2" smd custom
			(at 0 0.4445)
			(size 0.1397 0.1397)
			(layers "B.Cu" "B.Mask" "B.Paste")
			(net "P1V2_STBY")
			(options
				(clearance outline)
				(anchor circle)
			)
			(primitives
				(gr_poly
					(pts
						(arc
							(start -0.1778 0.2794)
							(mid -0.249642 0.249642)
							(end -0.2794 0.1778)
						)
						(arc
							(start -0.2794 -0.1778)
							(mid -0.249642 -0.249642)
							(end -0.1778 -0.2794)
						)
						(arc
							(start 0.1778 -0.2794)
							(mid 0.249642 -0.249642)
							(end 0.2794 -0.1778)
						)
						(arc
							(start 0.2794 0.1778)
							(mid 0.249642 0.249642)
							(end 0.1778 0.2794)
						)
					)
					(width 0)
					(fill yes)
				)
			)
		)
	)
	(footprint ""
		(layer "B.Cu")
		(at 175.768 -77.978 180)
		(property "Reference" "C344"
			(at 0 0 0)
			(layer "B.SilkS")
			(hide yes)
			(effects
				(font
					(size 1.27 1.27)
				)
				(justify mirror)
			)
		)
		(property "Value" "SC1U6D3V1MX-GP"
			(at -1.9177 2.0193 180)
			(unlocked yes)
			(layer "B.Fab")
			(hide yes)
			(effects
				(font
					(size 1.016 1.016)
					(thickness 0.1524)
				)
				(justify mirror)
			)
		)
		(property "Device Type" "C0201H14"
			(at -1.9177 0.4953 180)
			(unlocked yes)
			(layer "B.Fab")
			(hide yes)
			(effects
				(font
					(size 1.016 1.016)
					(thickness 0.1524)
				)
				(justify mirror)
			)
		)
		(duplicate_pad_numbers_are_jumpers no)
		(fp_rect
			(start 0.1524 0.3048)
			(end -0.1524 -0.3048)
			(stroke
				(width 0)
				(type default)
			)
			(fill no)
			(layer "B.CrtYd")
		)
		(fp_poly
			(pts
				(xy 0.2794 0.6477) (xy 0.2794 -0.6477) (xy -0.2794 -0.6477) (xy -0.2794 -0.1905) (xy -0.1524 -0.1905)
				(xy -0.1524 -0.3048) (xy 0.1524 -0.3048) (xy 0.1524 0.3048) (xy -0.1524 0.3048) (xy -0.1524 -0.1778)
				(xy -0.2794 -0.1778) (xy -0.2794 0.6477)
			)
			(stroke
				(width 0)
				(type default)
			)
			(fill no)
			(layer "B.CrtYd")
		)
		(fp_rect
			(start 0.2794 0.6477)
			(end -0.2794 -0.6477)
			(stroke
				(width 0)
				(type default)
			)
			(fill no)
			(layer "B.Fab")
		)
		(pad "1" smd custom
			(at 0 -0.2794)
			(size 0.0762 0.0762)
			(layers "B.Cu" "B.Mask" "B.Paste")
			(net "PLL_VDD")
			(options
				(clearance outline)
				(anchor circle)
			)
			(primitives
				(gr_poly
					(pts
						(arc
							(start 0.1524 0.127)
							(mid 0.137521 0.162921)
							(end 0.1016 0.1778)
						)
						(arc
							(start -0.1016 0.1778)
							(mid -0.137521 0.162921)
							(end -0.1524 0.127)
						)
						(arc
							(start -0.1524 -0.127)
							(mid -0.137521 -0.162921)
							(end -0.1016 -0.1778)
						)
						(arc
							(start 0.1016 -0.1778)
							(mid 0.137521 -0.162921)
							(end 0.1524 -0.127)
						)
					)
					(width 0)
					(fill yes)
				)
			)
		)
		(pad "2" smd custom
			(at 0 0.2794)
			(size 0.0762 0.0762)
			(layers "B.Cu" "B.Mask" "B.Paste")
			(net "GND")
			(options
				(clearance outline)
				(anchor circle)
			)
			(primitives
				(gr_poly
					(pts
						(arc
							(start 0.1524 0.127)
							(mid 0.137521 0.162921)
							(end 0.1016 0.1778)
						)
						(arc
							(start -0.1016 0.1778)
							(mid -0.137521 0.162921)
							(end -0.1524 0.127)
						)
						(arc
							(start -0.1524 -0.127)
							(mid -0.137521 -0.162921)
							(end -0.1016 -0.1778)
						)
						(arc
							(start 0.1016 -0.1778)
							(mid 0.137521 -0.162921)
							(end 0.1524 -0.127)
						)
					)
					(width 0)
					(fill yes)
				)
			)
		)
	)
	(footprint ""
		(layer "B.Cu")
		(at 82.169 -173.2026 90)
		(property "Reference" "C125"
			(at 0 0 90)
			(layer "B.SilkS")
			(hide yes)
			(effects
				(font
					(size 1.27 1.27)
				)
				(justify mirror)
			)
		)
		(property "Value" "SCD1U25V2KX-2-GP"
			(at -1.1811 -2.7051 90)
			(unlocked yes)
			(layer "B.Fab")
			(hide yes)
			(effects
				(font
					(size 1.016 1.016)
					(thickness 0.1524)
				)
				(justify mirror)
			)
		)
		(property "Device Type" "C402H22"
			(at -1.1811 -4.2291 90)
			(unlocked yes)
			(layer "B.Fab")
			(hide yes)
			(effects
				(font
					(size 1.016 1.016)
					(thickness 0.1524)
				)
				(justify mirror)
			)
		)
		(duplicate_pad_numbers_are_jumpers no)
		(fp_rect
			(start 0.4318 0.9525)
			(end -0.4318 -0.9525)
			(stroke
				(width 0)
				(type default)
			)
			(fill no)
			(layer "B.CrtYd")
		)
		(fp_rect
			(start 0.4318 0.9525)
			(end -0.4318 -0.9525)
			(stroke
				(width 0)
				(type default)
			)
			(fill no)
			(layer "B.Fab")
		)
		(pad "1" smd custom
			(at 0 -0.4445 270)
			(size 0.1524 0.1524)
			(layers "B.Cu" "B.Mask" "B.Paste")
			(net "P3V3_STBY")
			(options
				(clearance outline)
				(anchor circle)
			)
			(primitives
				(gr_poly
					(pts
						(arc
							(start 0.3048 0.2032)
							(mid 0.275042 0.275042)
							(end 0.2032 0.3048)
						)
						(arc
							(start -0.2032 0.3048)
							(mid -0.275042 0.275042)
							(end -0.3048 0.2032)
						)
						(arc
							(start -0.3048 -0.2032)
							(mid -0.275042 -0.275042)
							(end -0.2032 -0.3048)
						)
						(arc
							(start 0.2032 -0.3048)
							(mid 0.275042 -0.275042)
							(end 0.3048 -0.2032)
						)
					)
					(width 0)
					(fill yes)
				)
			)
		)
		(pad "2" smd custom
			(at 0 0.4445 270)
			(size 0.1524 0.1524)
			(layers "B.Cu" "B.Mask" "B.Paste")
			(net "GND")
			(options
				(clearance outline)
				(anchor circle)
			)
			(primitives
				(gr_poly
					(pts
						(arc
							(start 0.3048 0.2032)
							(mid 0.275042 0.275042)
							(end 0.2032 0.3048)
						)
						(arc
							(start -0.2032 0.3048)
							(mid -0.275042 0.275042)
							(end -0.3048 0.2032)
						)
						(arc
							(start -0.3048 -0.2032)
							(mid -0.275042 -0.275042)
							(end -0.2032 -0.3048)
						)
						(arc
							(start 0.2032 -0.3048)
							(mid 0.275042 -0.275042)
							(end 0.3048 -0.2032)
						)
					)
					(width 0)
					(fill yes)
				)
			)
		)
	)
	(footprint ""
		(layer "B.Cu")
		(at 168.656 -107.061 -90)
		(property "Reference" "C447"
			(at 0 0 90)
			(layer "B.SilkS")
			(hide yes)
			(effects
				(font
					(size 1.27 1.27)
				)
				(justify mirror)
			)
		)
		(property "Value" "SCD1U16V2KX-3GP"
			(at -1.1811 -2.7051 270)
			(unlocked yes)
			(layer "B.Fab")
			(hide yes)
			(effects
				(font
					(size 1.016 1.016)
					(thickness 0.1524)
				)
				(justify mirror)
			)
		)
		(property "Device Type" "C402H22"
			(at -1.1811 -4.2291 270)
			(unlocked yes)
			(layer "B.Fab")
			(hide yes)
			(effects
				(font
					(size 1.016 1.016)
					(thickness 0.1524)
				)
				(justify mirror)
			)
		)
		(duplicate_pad_numbers_are_jumpers no)
		(fp_rect
			(start 0.4318 0.9525)
			(end -0.4318 -0.9525)
			(stroke
				(width 0)
				(type default)
			)
			(fill no)
			(layer "B.CrtYd")
		)
		(fp_rect
			(start 0.4318 0.9525)
			(end -0.4318 -0.9525)
			(stroke
				(width 0)
				(type default)
			)
			(fill no)
			(layer "B.Fab")
		)
		(pad "1" smd custom
			(at 0 -0.4445 90)
			(size 0.1524 0.1524)
			(layers "B.Cu" "B.Mask" "B.Paste")
			(net "P1V8")
			(options
				(clearance outline)
				(anchor circle)
			)
			(primitives
				(gr_poly
					(pts
						(arc
							(start 0.3048 0.2032)
							(mid 0.275042 0.275042)
							(end 0.2032 0.3048)
						)
						(arc
							(start -0.2032 0.3048)
							(mid -0.275042 0.275042)
							(end -0.3048 0.2032)
						)
						(arc
							(start -0.3048 -0.2032)
							(mid -0.275042 -0.275042)
							(end -0.2032 -0.3048)
						)
						(arc
							(start 0.2032 -0.3048)
							(mid 0.275042 -0.275042)
							(end 0.3048 -0.2032)
						)
					)
					(width 0)
					(fill yes)
				)
			)
		)
		(pad "2" smd custom
			(at 0 0.4445 90)
			(size 0.1524 0.1524)
			(layers "B.Cu" "B.Mask" "B.Paste")
			(net "GND")
			(options
				(clearance outline)
				(anchor circle)
			)
			(primitives
				(gr_poly
					(pts
						(arc
							(start 0.3048 0.2032)
							(mid 0.275042 0.275042)
							(end 0.2032 0.3048)
						)
						(arc
							(start -0.2032 0.3048)
							(mid -0.275042 0.275042)
							(end -0.3048 0.2032)
						)
						(arc
							(start -0.3048 -0.2032)
							(mid -0.275042 -0.275042)
							(end -0.2032 -0.3048)
						)
						(arc
							(start 0.2032 -0.3048)
							(mid 0.275042 -0.275042)
							(end 0.3048 -0.2032)
						)
					)
					(width 0)
					(fill yes)
				)
			)
		)
	)
)
